(kicad_pcb
	(version 20260206)
	(generator "pcbnew")
	(generator_version "10.0")
	(general
		(thickness 1.6)
		(legacy_teardrops no)
	)
	(paper "A4")
	(title_block
		(title "01162023_DA0F0TEBIF0_F0T_Expander_BD_F_brd_V02_OCP.brd")
		(comment 1 "Grand Teton / footprints 2716-2721 of 9728")
	)
	(layers
		(0 "F.Cu" signal "TOP")
		(4 "In1.Cu" signal "GND")
		(6 "In2.Cu" signal "VCC")
		(8 "In3.Cu" signal "VCC1")
		(10 "In4.Cu" signal "GND1")
		(12 "In5.Cu" signal "IN1")
		(14 "In6.Cu" signal "GND2")
		(16 "In7.Cu" signal "IN2")
		(18 "In8.Cu" signal "GND3")
		(20 "In9.Cu" signal "IN3")
		(22 "In10.Cu" signal "GND4")
		(24 "In11.Cu" signal "IN4")
		(26 "In12.Cu" signal "GND5")
		(28 "In13.Cu" signal "IN5")
		(30 "In14.Cu" signal "GND6")
		(32 "In15.Cu" signal "IN6")
		(34 "In16.Cu" signal "GND7")
		(2 "B.Cu" signal "BOTTOM")
		(9 "F.Adhes" user "F.Adhesive")
		(11 "B.Adhes" user "B.Adhesive")
		(13 "F.Paste" user "Package Geometry/Pastemask Top")
		(15 "B.Paste" user "Package Geometry/Pastemask Bottom")
		(5 "F.SilkS" user "Ref Des/Silkscreen Top")
		(7 "B.SilkS" user "Ref Des/Silkscreen Bottom")
		(1 "F.Mask" user "Board Geometry/Soldermask Top")
		(3 "B.Mask" user "Board Geometry/Soldermask Bottom")
		(17 "Dwgs.User" user "User.Drawings")
		(19 "Cmts.User" user "User.Comments")
		(21 "Eco1.User" user "User.Eco1")
		(23 "Eco2.User" user "User.Eco2")
		(25 "Edge.Cuts" user "Board Geometry/Outline")
		(27 "Margin" user)
		(31 "F.CrtYd" user "Package Geometry/Place Bound Top")
		(29 "B.CrtYd" user "Package Geometry/Place Bound Bottom")
		(35 "F.Fab" user "Ref Des/Assembly Top")
		(33 "B.Fab" user "Ref Des/Assembly Bottom")
	)
	(footprint ""
		(layer "F.Cu")
		(at 223.586294 -176.52238)
		(property "Reference" "R3145"
			(at 0 0 0)
			(layer "F.SilkS")
			(hide yes)
			(effects
				(font
					(size 1.27 1.27)
				)
			)
		)
		(property "Value" ""
			(at 0 0 0)
			(layer "F.Fab")
			(effects
				(font
					(size 1.27 1.27)
				)
			)
		)
		(duplicate_pad_numbers_are_jumpers no)
		(fp_line
			(start -0.7874 -0.4064)
			(end 0.7874 -0.4064)
			(stroke
				(width 0.1524)
				(type default)
			)
			(layer "F.SilkS")
		)
		(fp_line
			(start -0.7874 0.4064)
			(end -0.7874 -0.4064)
			(stroke
				(width 0.1524)
				(type default)
			)
			(layer "F.SilkS")
		)
		(fp_line
			(start 0.7874 -0.4064)
			(end 0.7874 0.4064)
			(stroke
				(width 0.1524)
				(type default)
			)
			(layer "F.SilkS")
		)
		(fp_line
			(start 0.7874 0.4064)
			(end -0.7874 0.4064)
			(stroke
				(width 0.1524)
				(type default)
			)
			(layer "F.SilkS")
		)
		(fp_line
			(start -0.67945 -0.305054)
			(end -0.12065 -0.305054)
			(stroke
				(width 0.1)
				(type default)
			)
			(layer "F.Fab")
		)
		(fp_line
			(start -0.67945 0.3048)
			(end -0.67945 -0.305054)
			(stroke
				(width 0.1)
				(type default)
			)
			(layer "F.Fab")
		)
		(fp_line
			(start -0.12065 -0.305054)
			(end -0.12065 -0.2794)
			(stroke
				(width 0.1)
				(type default)
			)
			(layer "F.Fab")
		)
		(fp_line
			(start -0.12065 -0.2794)
			(end 0.12065 -0.2794)
			(stroke
				(width 0.1)
				(type default)
			)
			(layer "F.Fab")
		)
		(fp_line
			(start -0.12065 0.2794)
			(end -0.12065 0.3048)
			(stroke
				(width 0.1)
				(type default)
			)
			(layer "F.Fab")
		)
		(fp_line
			(start -0.12065 0.3048)
			(end -0.67945 0.3048)
			(stroke
				(width 0.1)
				(type default)
			)
			(layer "F.Fab")
		)
		(fp_line
			(start 0.120396 0.2794)
			(end -0.12065 0.2794)
			(stroke
				(width 0.1)
				(type default)
			)
			(layer "F.Fab")
		)
		(fp_line
			(start 0.120396 0.3048)
			(end 0.120396 0.2794)
			(stroke
				(width 0.1)
				(type default)
			)
			(layer "F.Fab")
		)
		(fp_line
			(start 0.12065 -0.3048)
			(end 0.67945 -0.3048)
			(stroke
				(width 0.1)
				(type default)
			)
			(layer "F.Fab")
		)
		(fp_line
			(start 0.12065 -0.2794)
			(end 0.12065 -0.3048)
			(stroke
				(width 0.1)
				(type default)
			)
			(layer "F.Fab")
		)
		(fp_line
			(start 0.67945 -0.3048)
			(end 0.67945 0.3048)
			(stroke
				(width 0.1)
				(type default)
			)
			(layer "F.Fab")
		)
		(fp_line
			(start 0.67945 0.3048)
			(end 0.120396 0.3048)
			(stroke
				(width 0.1)
				(type default)
			)
			(layer "F.Fab")
		)
		(pad "1" smd circle
			(at -0.40005 0)
			(size 0 0)
			(layers "F.Cu" "F.Mask" "F.Paste")
			(net "P3V3_AUX")
		)
		(pad "2" smd circle
			(at 0.40005 0)
			(size 0 0)
			(layers "F.Cu" "F.Mask" "F.Paste")
			(net "ADM1085_CEXT")
		)
	)
	(footprint ""
		(layer "F.Cu")
		(at 364.08487 -391.665968 -90)
		(property "Reference" "R6697"
			(at 0 0 270)
			(layer "F.SilkS")
			(hide yes)
			(effects
				(font
					(size 1.27 1.27)
				)
			)
		)
		(property "Value" ""
			(at 0 0 270)
			(layer "F.Fab")
			(effects
				(font
					(size 1.27 1.27)
				)
			)
		)
		(duplicate_pad_numbers_are_jumpers no)
		(fp_line
			(start -0.7874 0.4064)
			(end -0.7874 -0.4064)
			(stroke
				(width 0.1524)
				(type default)
			)
			(layer "F.SilkS")
		)
		(fp_line
			(start 0.7874 0.4064)
			(end -0.7874 0.4064)
			(stroke
				(width 0.1524)
				(type default)
			)
			(layer "F.SilkS")
		)
		(fp_line
			(start -0.7874 -0.4064)
			(end 0.7874 -0.4064)
			(stroke
				(width 0.1524)
				(type default)
			)
			(layer "F.SilkS")
		)
		(fp_line
			(start 0.7874 -0.4064)
			(end 0.7874 0.4064)
			(stroke
				(width 0.1524)
				(type default)
			)
			(layer "F.SilkS")
		)
		(fp_line
			(start -0.67945 0.3048)
			(end -0.67945 -0.305054)
			(stroke
				(width 0.1)
				(type default)
			)
			(layer "F.Fab")
		)
		(fp_line
			(start -0.12065 0.3048)
			(end -0.67945 0.3048)
			(stroke
				(width 0.1)
				(type default)
			)
			(layer "F.Fab")
		)
		(fp_line
			(start 0.120396 0.3048)
			(end 0.120396 0.2794)
			(stroke
				(width 0.1)
				(type default)
			)
			(layer "F.Fab")
		)
		(fp_line
			(start 0.67945 0.3048)
			(end 0.120396 0.3048)
			(stroke
				(width 0.1)
				(type default)
			)
			(layer "F.Fab")
		)
		(fp_line
			(start -0.12065 0.2794)
			(end -0.12065 0.3048)
			(stroke
				(width 0.1)
				(type default)
			)
			(layer "F.Fab")
		)
		(fp_line
			(start 0.120396 0.2794)
			(end -0.12065 0.2794)
			(stroke
				(width 0.1)
				(type default)
			)
			(layer "F.Fab")
		)
		(fp_line
			(start -0.12065 -0.2794)
			(end 0.12065 -0.2794)
			(stroke
				(width 0.1)
				(type default)
			)
			(layer "F.Fab")
		)
		(fp_line
			(start 0.12065 -0.2794)
			(end 0.12065 -0.3048)
			(stroke
				(width 0.1)
				(type default)
			)
			(layer "F.Fab")
		)
		(fp_line
			(start 0.12065 -0.3048)
			(end 0.67945 -0.3048)
			(stroke
				(width 0.1)
				(type default)
			)
			(layer "F.Fab")
		)
		(fp_line
			(start 0.67945 -0.3048)
			(end 0.67945 0.3048)
			(stroke
				(width 0.1)
				(type default)
			)
			(layer "F.Fab")
		)
		(fp_line
			(start -0.67945 -0.305054)
			(end -0.12065 -0.305054)
			(stroke
				(width 0.1)
				(type default)
			)
			(layer "F.Fab")
		)
		(fp_line
			(start -0.12065 -0.305054)
			(end -0.12065 -0.2794)
			(stroke
				(width 0.1)
				(type default)
			)
			(layer "F.Fab")
		)
		(pad "1" smd circle
			(at -0.40005 0 270)
			(size 0 0)
			(layers "F.Cu" "F.Mask" "F.Paste")
			(net "P3V3_AUX")
		)
		(pad "2" smd circle
			(at 0.40005 0 270)
			(size 0 0)
			(layers "F.Cu" "F.Mask" "F.Paste")
			(net "MB_3V3IO_RSVD1")
		)
	)
	(footprint ""
		(layer "F.Cu")
		(at 414.680908 -180.699918 180)
		(property "Reference" "R6431"
			(at 0 0 180)
			(layer "F.SilkS")
			(hide yes)
			(effects
				(font
					(size 1.27 1.27)
				)
			)
		)
		(property "Value" ""
			(at 0 0 180)
			(layer "F.Fab")
			(effects
				(font
					(size 1.27 1.27)
				)
			)
		)
		(duplicate_pad_numbers_are_jumpers no)
		(fp_line
			(start 0.7874 0.4064)
			(end -0.7874 0.4064)
			(stroke
				(width 0.1524)
				(type default)
			)
			(layer "F.SilkS")
		)
		(fp_line
			(start 0.7874 -0.4064)
			(end 0.7874 0.4064)
			(stroke
				(width 0.1524)
				(type default)
			)
			(layer "F.SilkS")
		)
		(fp_line
			(start -0.7874 0.4064)
			(end -0.7874 -0.4064)
			(stroke
				(width 0.1524)
				(type default)
			)
			(layer "F.SilkS")
		)
		(fp_line
			(start -0.7874 -0.4064)
			(end 0.7874 -0.4064)
			(stroke
				(width 0.1524)
				(type default)
			)
			(layer "F.SilkS")
		)
		(fp_line
			(start 0.67945 0.3048)
			(end 0.120396 0.3048)
			(stroke
				(width 0.1)
				(type default)
			)
			(layer "F.Fab")
		)
		(fp_line
			(start 0.67945 -0.3048)
			(end 0.67945 0.3048)
			(stroke
				(width 0.1)
				(type default)
			)
			(layer "F.Fab")
		)
		(fp_line
			(start 0.12065 -0.2794)
			(end 0.12065 -0.3048)
			(stroke
				(width 0.1)
				(type default)
			)
			(layer "F.Fab")
		)
		(fp_line
			(start 0.12065 -0.3048)
			(end 0.67945 -0.3048)
			(stroke
				(width 0.1)
				(type default)
			)
			(layer "F.Fab")
		)
		(fp_line
			(start 0.120396 0.3048)
			(end 0.120396 0.2794)
			(stroke
				(width 0.1)
				(type default)
			)
			(layer "F.Fab")
		)
		(fp_line
			(start 0.120396 0.2794)
			(end -0.12065 0.2794)
			(stroke
				(width 0.1)
				(type default)
			)
			(layer "F.Fab")
		)
		(fp_line
			(start -0.12065 0.3048)
			(end -0.67945 0.3048)
			(stroke
				(width 0.1)
				(type default)
			)
			(layer "F.Fab")
		)
		(fp_line
			(start -0.12065 0.2794)
			(end -0.12065 0.3048)
			(stroke
				(width 0.1)
				(type default)
			)
			(layer "F.Fab")
		)
		(fp_line
			(start -0.12065 -0.2794)
			(end 0.12065 -0.2794)
			(stroke
				(width 0.1)
				(type default)
			)
			(layer "F.Fab")
		)
		(fp_line
			(start -0.12065 -0.305054)
			(end -0.12065 -0.2794)
			(stroke
				(width 0.1)
				(type default)
			)
			(layer "F.Fab")
		)
		(fp_line
			(start -0.67945 0.3048)
			(end -0.67945 -0.305054)
			(stroke
				(width 0.1)
				(type default)
			)
			(layer "F.Fab")
		)
		(fp_line
			(start -0.67945 -0.305054)
			(end -0.12065 -0.305054)
			(stroke
				(width 0.1)
				(type default)
			)
			(layer "F.Fab")
		)
		(pad "1" smd circle
			(at -0.40005 0 180)
			(size 0 0)
			(layers "F.Cu" "F.Mask" "F.Paste")
			(net "FPGA_PEX1_MODE_SEL1_D_N")
		)
		(pad "2" smd circle
			(at 0.40005 0 180)
			(size 0 0)
			(layers "F.Cu" "F.Mask" "F.Paste")
			(net "P3V3_AUX")
		)
	)
	(footprint ""
		(layer "F.Cu")
		(at 377.156218 -32.848042 -90)
		(property "Reference" "R6103"
			(at 0 0 270)
			(layer "F.SilkS")
			(hide yes)
			(effects
				(font
					(size 1.27 1.27)
				)
			)
		)
		(property "Value" ""
			(at 0 0 270)
			(layer "F.Fab")
			(effects
				(font
					(size 1.27 1.27)
				)
			)
		)
		(duplicate_pad_numbers_are_jumpers no)
		(fp_line
			(start -0.7874 0.4064)
			(end -0.7874 -0.4064)
			(stroke
				(width 0.1524)
				(type default)
			)
			(layer "F.SilkS")
		)
		(fp_line
			(start 0.7874 0.4064)
			(end -0.7874 0.4064)
			(stroke
				(width 0.1524)
				(type default)
			)
			(layer "F.SilkS")
		)
		(fp_line
			(start -0.7874 -0.4064)
			(end 0.7874 -0.4064)
			(stroke
				(width 0.1524)
				(type default)
			)
			(layer "F.SilkS")
		)
		(fp_line
			(start 0.7874 -0.4064)
			(end 0.7874 0.4064)
			(stroke
				(width 0.1524)
				(type default)
			)
			(layer "F.SilkS")
		)
		(fp_line
			(start -0.67945 0.3048)
			(end -0.67945 -0.305054)
			(stroke
				(width 0.1)
				(type default)
			)
			(layer "F.Fab")
		)
		(fp_line
			(start -0.12065 0.3048)
			(end -0.67945 0.3048)
			(stroke
				(width 0.1)
				(type default)
			)
			(layer "F.Fab")
		)
		(fp_line
			(start 0.120396 0.3048)
			(end 0.120396 0.2794)
			(stroke
				(width 0.1)
				(type default)
			)
			(layer "F.Fab")
		)
		(fp_line
			(start 0.67945 0.3048)
			(end 0.120396 0.3048)
			(stroke
				(width 0.1)
				(type default)
			)
			(layer "F.Fab")
		)
		(fp_line
			(start -0.12065 0.2794)
			(end -0.12065 0.3048)
			(stroke
				(width 0.1)
				(type default)
			)
			(layer "F.Fab")
		)
		(fp_line
			(start 0.120396 0.2794)
			(end -0.12065 0.2794)
			(stroke
				(width 0.1)
				(type default)
			)
			(layer "F.Fab")
		)
		(fp_line
			(start -0.12065 -0.2794)
			(end 0.12065 -0.2794)
			(stroke
				(width 0.1)
				(type default)
			)
			(layer "F.Fab")
		)
		(fp_line
			(start 0.12065 -0.2794)
			(end 0.12065 -0.3048)
			(stroke
				(width 0.1)
				(type default)
			)
			(layer "F.Fab")
		)
		(fp_line
			(start 0.12065 -0.3048)
			(end 0.67945 -0.3048)
			(stroke
				(width 0.1)
				(type default)
			)
			(layer "F.Fab")
		)
		(fp_line
			(start 0.67945 -0.3048)
			(end 0.67945 0.3048)
			(stroke
				(width 0.1)
				(type default)
			)
			(layer "F.Fab")
		)
		(fp_line
			(start -0.67945 -0.305054)
			(end -0.12065 -0.305054)
			(stroke
				(width 0.1)
				(type default)
			)
			(layer "F.Fab")
		)
		(fp_line
			(start -0.12065 -0.305054)
			(end -0.12065 -0.2794)
			(stroke
				(width 0.1)
				(type default)
			)
			(layer "F.Fab")
		)
		(pad "1" smd circle
			(at -0.40005 0 270)
			(size 0 0)
			(layers "F.Cu" "F.Mask" "F.Paste")
			(net "SSD13_AUX_P3V3_EN_R")
		)
		(pad "2" smd circle
			(at 0.40005 0 270)
			(size 0 0)
			(layers "F.Cu" "F.Mask" "F.Paste")
			(net "P3V3_SSD13_CO_EN")
		)
	)
	(footprint ""
		(layer "F.Cu")
		(at 221.251272 -140.894562 180)
		(property "Reference" "R4197"
			(at 0 0 180)
			(layer "F.SilkS")
			(hide yes)
			(effects
				(font
					(size 1.27 1.27)
				)
			)
		)
		(property "Value" ""
			(at 0 0 180)
			(layer "F.Fab")
			(effects
				(font
					(size 1.27 1.27)
				)
			)
		)
		(duplicate_pad_numbers_are_jumpers no)
		(fp_line
			(start 0.7874 0.4064)
			(end -0.7874 0.4064)
			(stroke
				(width 0.1524)
				(type default)
			)
			(layer "F.SilkS")
		)
		(fp_line
			(start 0.7874 -0.4064)
			(end 0.7874 0.4064)
			(stroke
				(width 0.1524)
				(type default)
			)
			(layer "F.SilkS")
		)
		(fp_line
			(start -0.7874 0.4064)
			(end -0.7874 -0.4064)
			(stroke
				(width 0.1524)
				(type default)
			)
			(layer "F.SilkS")
		)
		(fp_line
			(start -0.7874 -0.4064)
			(end 0.7874 -0.4064)
			(stroke
				(width 0.1524)
				(type default)
			)
			(layer "F.SilkS")
		)
		(fp_line
			(start 0.67945 0.3048)
			(end 0.120396 0.3048)
			(stroke
				(width 0.1)
				(type default)
			)
			(layer "F.Fab")
		)
		(fp_line
			(start 0.67945 -0.3048)
			(end 0.67945 0.3048)
			(stroke
				(width 0.1)
				(type default)
			)
			(layer "F.Fab")
		)
		(fp_line
			(start 0.12065 -0.2794)
			(end 0.12065 -0.3048)
			(stroke
				(width 0.1)
				(type default)
			)
			(layer "F.Fab")
		)
		(fp_line
			(start 0.12065 -0.3048)
			(end 0.67945 -0.3048)
			(stroke
				(width 0.1)
				(type default)
			)
			(layer "F.Fab")
		)
		(fp_line
			(start 0.120396 0.3048)
			(end 0.120396 0.2794)
			(stroke
				(width 0.1)
				(type default)
			)
			(layer "F.Fab")
		)
		(fp_line
			(start 0.120396 0.2794)
			(end -0.12065 0.2794)
			(stroke
				(width 0.1)
				(type default)
			)
			(layer "F.Fab")
		)
		(fp_line
			(start -0.12065 0.3048)
			(end -0.67945 0.3048)
			(stroke
				(width 0.1)
				(type default)
			)
			(layer "F.Fab")
		)
		(fp_line
			(start -0.12065 0.2794)
			(end -0.12065 0.3048)
			(stroke
				(width 0.1)
				(type default)
			)
			(layer "F.Fab")
		)
		(fp_line
			(start -0.12065 -0.2794)
			(end 0.12065 -0.2794)
			(stroke
				(width 0.1)
				(type default)
			)
			(layer "F.Fab")
		)
		(fp_line
			(start -0.12065 -0.305054)
			(end -0.12065 -0.2794)
			(stroke
				(width 0.1)
				(type default)
			)
			(layer "F.Fab")
		)
		(fp_line
			(start -0.67945 0.3048)
			(end -0.67945 -0.305054)
			(stroke
				(width 0.1)
				(type default)
			)
			(layer "F.Fab")
		)
		(fp_line
			(start -0.67945 -0.305054)
			(end -0.12065 -0.305054)
			(stroke
				(width 0.1)
				(type default)
			)
			(layer "F.Fab")
		)
		(pad "1" smd circle
			(at -0.40005 0 180)
			(size 0 0)
			(layers "F.Cu" "F.Mask" "F.Paste")
			(net "FM_CK440_PEX_DEV_25M_EN")
		)
		(pad "2" smd circle
			(at 0.40005 0 180)
			(size 0 0)
			(layers "F.Cu" "F.Mask" "F.Paste")
			(net "P3V3")
		)
	)
	(footprint ""
		(layer "F.Cu")
		(at 218.156028 -117.90045 90)
		(property "Reference" "PC622"
			(at 0 0 90)
			(layer "F.SilkS")
			(hide yes)
			(effects
				(font
					(size 1.27 1.27)
				)
			)
		)
		(property "Value" ""
			(at 0 0 90)
			(layer "F.Fab")
			(effects
				(font
					(size 1.27 1.27)
				)
			)
		)
		(duplicate_pad_numbers_are_jumpers no)
		(fp_line
			(start 1.524 -0.762)
			(end 1.524 0.762)
			(stroke
				(width 0.1524)
				(type default)
			)
			(layer "F.SilkS")
		)
		(fp_line
			(start -1.524 -0.762)
			(end 1.524 -0.762)
			(stroke
				(width 0.1524)
				(type default)
			)
			(layer "F.SilkS")
		)
		(fp_line
			(start 1.524 0.762)
			(end -1.524 0.762)
			(stroke
				(width 0.1524)
				(type default)
			)
			(layer "F.SilkS")
		)
		(fp_line
			(start -1.524 0.762)
			(end -1.524 -0.762)
			(stroke
				(width 0.1524)
				(type default)
			)
			(layer "F.SilkS")
		)
		(fp_line
			(start 1.1049 -0.724916)
			(end -1.1049 -0.724916)
			(stroke
				(width 0.1)
				(type default)
			)
			(layer "F.Fab")
		)
		(fp_line
			(start -1.1049 -0.724916)
			(end -1.1049 0.724916)
			(stroke
				(width 0.1)
				(type default)
			)
			(layer "F.Fab")
		)
		(fp_line
			(start 1.1049 0.724916)
			(end 1.1049 -0.724916)
			(stroke
				(width 0.1)
				(type default)
			)
			(layer "F.Fab")
		)
		(fp_line
			(start -1.1049 0.724916)
			(end 1.1049 0.724916)
			(stroke
				(width 0.1)
				(type default)
			)
			(layer "F.Fab")
		)
		(pad "1" smd rect
			(at -0.889 0 270)
			(size 1.016 1.27)
			(layers "F.Cu" "F.Mask" "F.Paste")
			(net "P12V_NIC3_R")
		)
		(pad "2" smd rect
			(at 0.889 0 270)
			(size 1.016 1.27)
			(layers "F.Cu" "F.Mask" "F.Paste")
			(net "GND")
		)
	)
)
